FILE_TYPE=LIBRARY_PARTS;
primitive 'CSD87384M','CSD87384M_SM';
  pin
    'BG':
      PIN_NUMBER='(4)';
      INPUT_LOAD='(-0.01,0.01)';
    'PGND':
      PIN_NUMBER='(3)';
      PIN_TYPE='GROUND';
      NO_LOAD_CHECK='BOTH';
      NO_IO_CHECK='BOTH';
      ALLOW_CONNECT='TRUE';
    'TG':
      PIN_NUMBER='(1)';
      INPUT_LOAD='(-0.01,0.01)';
    'VIN':
      PIN_NUMBER='(2)';
      INPUT_LOAD='(-0.01,0.01)';
    'VSW':
      PIN_NUMBER='(5)';
      OUTPUT_LOAD='(1.0,-1.0)';
  end_pin;
  body
    PART_NAME='CSD87384M';
    PHYS_DES_PREFIX='EU';
  end_body;
end_primitive;

END.
